(kicad_pcb
	(version 20260206)
	(generator "pcbnew")
	(generator_version "10.0")
	(general
		(thickness 1.6)
		(legacy_teardrops no)
	)
	(paper "A4")
	(title_block
		(title "peb — Lightning_PEB_BRD.brd")
		(comment 1 "Lightning (Wiwynn / Facebook NVMe JBOF) / footprints 184-188 of 2563")
	)
	(layers
		(0 "F.Cu" signal "TOP")
		(4 "In1.Cu" signal "L2GND")
		(6 "In2.Cu" signal "L3")
		(8 "In3.Cu" signal "L4VCC")
		(10 "In4.Cu" signal "L5VCC")
		(12 "In5.Cu" signal "L6")
		(14 "In6.Cu" signal "L7GND")
		(2 "B.Cu" signal "BOTTOM")
		(9 "F.Adhes" user "F.Adhesive")
		(11 "B.Adhes" user "B.Adhesive")
		(13 "F.Paste" user "Package Geometry/Pastemask Top")
		(15 "B.Paste" user "Package Geometry/Pastemask Bottom")
		(5 "F.SilkS" user "Ref Des/Silkscreen Top")
		(7 "B.SilkS" user "Ref Des/Silkscreen Bottom")
		(1 "F.Mask" user "Board Geometry/Soldermask Top")
		(3 "B.Mask" user "Board Geometry/Soldermask Bottom")
		(17 "Dwgs.User" user "User.Drawings")
		(19 "Cmts.User" user "User.Comments")
		(21 "Eco1.User" user "User.Eco1")
		(23 "Eco2.User" user "User.Eco2")
		(25 "Edge.Cuts" user "Board Geometry/Outline")
		(27 "Margin" user)
		(31 "F.CrtYd" user "Package Geometry/Place Bound Top")
		(29 "B.CrtYd" user "Package Geometry/Place Bound Bottom")
		(35 "F.Fab" user "Ref Des/Assembly Top")
		(33 "B.Fab" user "Ref Des/Assembly Bottom")
	)
	(footprint ""
		(layer "F.Cu")
		(at 39.878 -198.882 -90)
		(property "Reference" "C697"
			(at 0 0 270)
			(layer "F.SilkS")
			(hide yes)
			(effects
				(font
					(size 1.27 1.27)
				)
			)
		)
		(property "Value" "SC220P50V3JN-GP"
			(at 0 -2.8194 270)
			(unlocked yes)
			(layer "F.Fab")
			(hide yes)
			(effects
				(font
					(size 1.016 1.016)
					(thickness 0.1524)
				)
			)
		)
		(property "Device Type" "C603H36"
			(at 0 -4.3434 270)
			(unlocked yes)
			(layer "F.Fab")
			(hide yes)
			(effects
				(font
					(size 1.016 1.016)
					(thickness 0.1524)
				)
			)
		)
		(duplicate_pad_numbers_are_jumpers no)
		(fp_line
			(start 0.508 0)
			(end -0.508 0)
			(stroke
				(width 0.2032)
				(type default)
			)
			(layer "F.SilkS")
		)
		(fp_rect
			(start -0.5842 1.3335)
			(end 0.5842 -1.3335)
			(stroke
				(width 0)
				(type default)
			)
			(fill no)
			(layer "F.CrtYd")
		)
		(fp_rect
			(start -0.5842 1.3335)
			(end 0.5842 -1.3335)
			(stroke
				(width 0)
				(type default)
			)
			(fill no)
			(layer "F.Fab")
		)
		(pad "1" smd custom
			(at 0 -0.762 270)
			(size 0.2159 0.2159)
			(layers "F.Cu" "F.Mask" "F.Paste")
			(net "BMC_I2C6_C_FCB_SDA_R")
			(options
				(clearance outline)
				(anchor circle)
			)
			(primitives
				(gr_poly
					(pts
						(arc
							(start -0.3302 -0.4318)
							(mid -0.402042 -0.402042)
							(end -0.4318 -0.3302)
						)
						(arc
							(start -0.4318 0.3302)
							(mid -0.402042 0.402042)
							(end -0.3302 0.4318)
						)
						(arc
							(start 0.3302 0.4318)
							(mid 0.402042 0.402042)
							(end 0.4318 0.3302)
						)
						(arc
							(start 0.4318 -0.3302)
							(mid 0.402042 -0.402042)
							(end 0.3302 -0.4318)
						)
					)
					(width 0)
					(fill yes)
				)
			)
		)
		(pad "2" smd custom
			(at 0 0.762 270)
			(size 0.2159 0.2159)
			(layers "F.Cu" "F.Mask" "F.Paste")
			(net "GND")
			(options
				(clearance outline)
				(anchor circle)
			)
			(primitives
				(gr_poly
					(pts
						(arc
							(start -0.3302 -0.4318)
							(mid -0.402042 -0.402042)
							(end -0.4318 -0.3302)
						)
						(arc
							(start -0.4318 0.3302)
							(mid -0.402042 0.402042)
							(end -0.3302 0.4318)
						)
						(arc
							(start 0.3302 0.4318)
							(mid 0.402042 0.402042)
							(end 0.4318 0.3302)
						)
						(arc
							(start 0.4318 -0.3302)
							(mid 0.402042 -0.402042)
							(end 0.3302 -0.4318)
						)
					)
					(width 0)
					(fill yes)
				)
			)
		)
	)
	(footprint ""
		(layer "F.Cu")
		(at 26.64206 -62.999874)
		(property "Reference" "CN11"
			(at 0 0 0)
			(layer "F.SilkS")
			(hide yes)
			(effects
				(font
					(size 1.27 1.27)
				)
			)
		)
		(property "Value" "FCI-CONN11-2-GP"
			(at -7.4803 1.3589 0)
			(unlocked yes)
			(layer "F.Fab")
			(hide yes)
			(effects
				(font
					(size 1.016 1.016)
					(thickness 0.1524)
				)
			)
		)
		(property "Device Type" "91932-31111LF"
			(at -7.4803 -0.1651 0)
			(unlocked yes)
			(layer "F.Fab")
			(hide yes)
			(effects
				(font
					(size 1.016 1.016)
					(thickness 0.1524)
				)
			)
		)
		(duplicate_pad_numbers_are_jumpers no)
		(fp_line
			(start -5.4102 -3.556)
			(end -5.4102 3.556)
			(stroke
				(width 0.1524)
				(type default)
			)
			(layer "F.SilkS")
		)
		(fp_line
			(start -5.4102 3.556)
			(end 5.4102 3.556)
			(stroke
				(width 0.1524)
				(type default)
			)
			(layer "F.SilkS")
		)
		(fp_line
			(start -2.8321 3.6449)
			(end -2.2479 3.6449)
			(stroke
				(width 0.3302)
				(type default)
			)
			(layer "F.SilkS")
		)
		(fp_line
			(start 5.4102 -3.556)
			(end -5.4102 -3.556)
			(stroke
				(width 0.1524)
				(type default)
			)
			(layer "F.SilkS")
		)
		(fp_line
			(start 5.4102 3.556)
			(end 5.4102 -3.556)
			(stroke
				(width 0.1524)
				(type default)
			)
			(layer "F.SilkS")
		)
		(fp_poly
			(pts
				(xy -2.546096 3.612642) (xy -3.181096 4.247642) (xy -1.911096 4.247642)
			)
			(stroke
				(width 0)
				(type default)
			)
			(fill yes)
			(layer "F.SilkS")
		)
		(fp_poly
			(pts
				(xy -2.8067 1.08839)
				(arc
					(start -2.8067 -0.422402)
					(mid -2.451868 -0.675672)
					(end -2.3114 -1.08839)
				)
				(arc
					(start 2.3114 -1.08839)
					(mid 2.451818 -0.675634)
					(end 2.8067 -0.422402)
				)
				(xy 2.8067 1.08839)
			)
			(stroke
				(width 0)
				(type default)
			)
			(fill yes)
			(layer "F.SilkS")
		)
		(fp_rect
			(start -5.1562 2.794)
			(end 5.1562 -2.794)
			(stroke
				(width 0)
				(type default)
			)
			(fill no)
			(layer "F.CrtYd")
		)
		(fp_poly
			(pts
				(xy 5.6642 -2.794) (xy -5.1562 -2.794) (xy -5.1562 2.794) (xy 5.1562 2.794) (xy 5.1562 -2.7813)
				(xy 5.6642 -2.7813) (xy 5.6642 3.81) (xy -5.6642 3.81) (xy -5.6642 -3.81) (xy 5.6642 -3.81)
			)
			(stroke
				(width 0)
				(type default)
			)
			(fill no)
			(layer "F.CrtYd")
		)
		(fp_rect
			(start -5.6642 3.81)
			(end 5.6642 -3.81)
			(stroke
				(width 0)
				(type default)
			)
			(fill no)
			(layer "F.Fab")
		)
		(pad "" np_thru_hole circle
			(at -3.0226 -1.100074)
			(size 0.254 0.254)
			(drill 0.8128)
			(layers "*.Cu" "*.Mask")
			(clearance 0.635)
			(thermal_gap 0.635)
		)
		(pad "" np_thru_hole circle
			(at 3.0226 -1.100074)
			(size 0.254 0.254)
			(drill 0.8128)
			(layers "*.Cu" "*.Mask")
			(clearance 0.635)
			(thermal_gap 0.635)
		)
		(pad "1" smd rect
			(at -2.500122 2.29489)
			(size 0.6096 2.0066)
			(layers "F.Cu" "F.Mask" "F.Paste")
			(net "Net_14")
		)
		(pad "2" smd rect
			(at -1.500124 2.29489)
			(size 0.6096 2.0066)
			(layers "F.Cu" "F.Mask" "F.Paste")
			(net "Net_13")
		)
		(pad "3" smd rect
			(at -0.500126 2.29489)
			(size 0.6096 2.0066)
			(layers "F.Cu" "F.Mask" "F.Paste")
			(net "Net_12")
		)
		(pad "4" smd rect
			(at 0.500126 2.29489)
			(size 0.6096 2.0066)
			(layers "F.Cu" "F.Mask" "F.Paste")
			(net "Net_11")
		)
		(pad "5" smd rect
			(at 1.500124 2.29489)
			(size 0.6096 2.0066)
			(layers "F.Cu" "F.Mask" "F.Paste")
			(net "Net_10")
		)
		(pad "6" smd rect
			(at 2.500122 2.29489)
			(size 0.6096 2.0066)
			(layers "F.Cu" "F.Mask" "F.Paste")
			(net "I2C_TPM_SDA")
		)
		(pad "7" smd rect
			(at -1.999996 -2.29489)
			(size 0.6096 2.0066)
			(layers "F.Cu" "F.Mask" "F.Paste")
			(net "P3V3_STBY")
		)
		(pad "8" smd rect
			(at -0.999998 -2.29489)
			(size 0.6096 2.0066)
			(layers "F.Cu" "F.Mask" "F.Paste")
			(net "FM_TPM_PRES_RST_N")
		)
		(pad "9" smd rect
			(at 0 -2.29489)
			(size 0.6096 2.0066)
			(layers "F.Cu" "F.Mask" "F.Paste")
			(net "Net_15")
		)
		(pad "10" smd rect
			(at 0.999998 -2.29489)
			(size 0.6096 2.0066)
			(layers "F.Cu" "F.Mask" "F.Paste")
			(net "I2C_TPM_SCL")
		)
		(pad "11" smd rect
			(at 1.999996 -2.29489)
			(size 0.6096 2.0066)
			(layers "F.Cu" "F.Mask" "F.Paste")
			(net "GND")
		)
		(pad "G1" smd custom
			(at -4.219956 0)
			(size 0.34925 0.34925)
			(layers "F.Cu" "F.Mask" "F.Paste")
			(net "GND")
			(options
				(clearance outline)
				(anchor circle)
			)
			(primitives
				(gr_poly
					(pts
						(xy -0.6985 2.921) (xy -0.6985 -2.921) (xy 0.6985 -2.921)
						(arc
							(start 0.6985 -1.610106)
							(mid 0.482924 -1.100074)
							(end 0.6985 -0.590042)
						)
						(xy 0.6985 2.921)
					)
					(width 0)
					(fill yes)
				)
			)
		)
		(pad "G2" smd custom
			(at 4.219956 0)
			(size 0.34925 0.34925)
			(layers "F.Cu" "F.Mask" "F.Paste")
			(net "GND")
			(options
				(clearance outline)
				(anchor circle)
			)
			(primitives
				(gr_poly
					(pts
						(xy -0.6985 2.921)
						(arc
							(start -0.6985 -0.590042)
							(mid -0.482924 -1.100074)
							(end -0.6985 -1.610106)
						)
						(xy -0.6985 -2.921) (xy 0.6985 -2.921) (xy 0.6985 2.921)
					)
					(width 0)
					(fill yes)
				)
			)
		)
		(zone
			(layer "F.Cu")
			(hatch none 0.5)
			(connect_pads
				(clearance 0)
			)
			(min_thickness 0.25)
			(keepout
				(tracks allowed)
				(vias not_allowed)
				(pads allowed)
				(copperpour not_allowed)
				(footprints allowed)
			)
			(placement
				(enabled no)
				(sheetname "")
			)
			(fill
				(thermal_gap 0.5)
				(thermal_bridge_width 0.5)
				(island_removal_mode 0)
			)
			(polygon
				(pts
					(xy 23.83536 -61.708284) (xy 29.44876 -61.708284) (xy 29.44876 -64.291464) (xy 23.83536 -64.291464)
				)
			)
		)
		(zone
			(layer "F.Cu")
			(hatch none 0.5)
			(connect_pads
				(clearance 0)
			)
			(min_thickness 0.25)
			(keepout
				(tracks not_allowed)
				(vias allowed)
				(pads allowed)
				(copperpour not_allowed)
				(footprints allowed)
			)
			(placement
				(enabled no)
				(sheetname "")
			)
			(fill
				(thermal_gap 0.5)
				(thermal_bridge_width 0.5)
				(island_removal_mode 0)
			)
			(polygon
				(pts
					(xy 23.83536 -61.708284) (xy 29.44876 -61.708284) (xy 29.44876 -64.291464) (xy 23.83536 -64.291464)
				)
			)
		)
		(zone
			(layer "F.Cu")
			(hatch none 0.5)
			(connect_pads
				(clearance 0)
			)
			(min_thickness 0.25)
			(keepout
				(tracks allowed)
				(vias not_allowed)
				(pads allowed)
				(copperpour not_allowed)
				(footprints allowed)
			)
			(placement
				(enabled no)
				(sheetname "")
			)
			(fill
				(thermal_gap 0.5)
				(thermal_bridge_width 0.5)
				(island_removal_mode 0)
			)
			(polygon
				(pts
					(xy 23.83536 -61.708284) (xy 29.44876 -61.708284) (xy 29.44876 -62.216284) (xy 23.83536 -62.216284)
				)
			)
		)
		(zone
			(layer "F.Cu")
			(hatch none 0.5)
			(connect_pads
				(clearance 0)
			)
			(min_thickness 0.25)
			(keepout
				(tracks allowed)
				(vias not_allowed)
				(pads allowed)
				(copperpour not_allowed)
				(footprints allowed)
			)
			(placement
				(enabled no)
				(sheetname "")
			)
			(fill
				(thermal_gap 0.5)
				(thermal_bridge_width 0.5)
				(island_removal_mode 0)
			)
			(polygon
				(pts
					(xy 24.33066 -63.783464) (xy 28.95346 -63.783464) (xy 28.95346 -64.291464) (xy 24.33066 -64.291464)
				)
			)
		)
		(zone
			(layers "F.Cu" "B.Cu" "In1.Cu" "In2.Cu" "In3.Cu" "In4.Cu" "In5.Cu" "In6.Cu")
			(hatch none 0.5)
			(connect_pads
				(clearance 0)
			)
			(min_thickness 0.25)
			(keepout
				(tracks not_allowed)
				(vias allowed)
				(pads allowed)
				(copperpour not_allowed)
				(footprints allowed)
			)
			(placement
				(enabled no)
				(sheetname "")
			)
			(fill
				(thermal_gap 0.5)
				(thermal_bridge_width 0.5)
				(island_removal_mode 0)
			)
			(polygon
				(pts
					(arc
						(start 24.33066 -64.099948)
						(mid 22.90826 -64.099948)
						(end 24.33066 -64.099948)
					)
				)
			)
		)
		(zone
			(layers "F.Cu" "B.Cu" "In1.Cu" "In2.Cu" "In3.Cu" "In4.Cu" "In5.Cu" "In6.Cu")
			(hatch none 0.5)
			(connect_pads
				(clearance 0)
			)
			(min_thickness 0.25)
			(keepout
				(tracks not_allowed)
				(vias allowed)
				(pads allowed)
				(copperpour not_allowed)
				(footprints allowed)
			)
			(placement
				(enabled no)
				(sheetname "")
			)
			(fill
				(thermal_gap 0.5)
				(thermal_bridge_width 0.5)
				(island_removal_mode 0)
			)
			(polygon
				(pts
					(arc
						(start 30.37586 -64.099948)
						(mid 28.95346 -64.099948)
						(end 30.37586 -64.099948)
					)
				)
			)
		)
	)
	(footprint ""
		(layer "F.Cu")
		(at 29.048456 -32.841946)
		(property "Reference" "R446"
			(at 0 0 0)
			(layer "F.SilkS")
			(hide yes)
			(effects
				(font
					(size 1.27 1.27)
				)
			)
		)
		(property "Value" "0R3J-0-U-GP"
			(at -0.0254 -2.5146 0)
			(unlocked yes)
			(layer "F.Fab")
			(hide yes)
			(effects
				(font
					(size 1.016 1.016)
					(thickness 0.1524)
				)
			)
		)
		(property "Device Type" "R603H22"
			(at -0.0254 -4.0386 0)
			(unlocked yes)
			(layer "F.Fab")
			(hide yes)
			(effects
				(font
					(size 1.016 1.016)
					(thickness 0.1524)
				)
			)
		)
		(duplicate_pad_numbers_are_jumpers no)
		(fp_line
			(start -0.4826 0)
			(end -0.2032 0)
			(stroke
				(width 0.2032)
				(type default)
			)
			(layer "F.SilkS")
		)
		(fp_line
			(start 0.2032 0)
			(end 0.4826 0)
			(stroke
				(width 0.2032)
				(type default)
			)
			(layer "F.SilkS")
		)
		(fp_rect
			(start -0.5842 1.3335)
			(end 0.5842 -1.3335)
			(stroke
				(width 0)
				(type default)
			)
			(fill no)
			(layer "F.CrtYd")
		)
		(fp_rect
			(start -0.5842 1.3335)
			(end 0.5842 -1.3335)
			(stroke
				(width 0)
				(type default)
			)
			(fill no)
			(layer "F.Fab")
		)
		(pad "1" smd custom
			(at 0 -0.762)
			(size 0.2159 0.2159)
			(layers "F.Cu" "F.Mask" "F.Paste")
			(net "AGND_USB")
			(options
				(clearance outline)
				(anchor circle)
			)
			(primitives
				(gr_poly
					(pts
						(arc
							(start -0.3302 -0.4318)
							(mid -0.402042 -0.402042)
							(end -0.4318 -0.3302)
						)
						(arc
							(start -0.4318 0.3302)
							(mid -0.402042 0.402042)
							(end -0.3302 0.4318)
						)
						(arc
							(start 0.3302 0.4318)
							(mid 0.402042 0.402042)
							(end 0.4318 0.3302)
						)
						(arc
							(start 0.4318 -0.3302)
							(mid 0.402042 -0.402042)
							(end 0.3302 -0.4318)
						)
					)
					(width 0)
					(fill yes)
				)
			)
		)
		(pad "2" smd custom
			(at 0 0.762)
			(size 0.2159 0.2159)
			(layers "F.Cu" "F.Mask" "F.Paste")
			(net "GND")
			(options
				(clearance outline)
				(anchor circle)
			)
			(primitives
				(gr_poly
					(pts
						(arc
							(start -0.3302 -0.4318)
							(mid -0.402042 -0.402042)
							(end -0.4318 -0.3302)
						)
						(arc
							(start -0.4318 0.3302)
							(mid -0.402042 0.402042)
							(end -0.3302 0.4318)
						)
						(arc
							(start 0.3302 0.4318)
							(mid 0.402042 0.402042)
							(end 0.4318 0.3302)
						)
						(arc
							(start 0.4318 -0.3302)
							(mid 0.402042 -0.402042)
							(end 0.3302 -0.4318)
						)
					)
					(width 0)
					(fill yes)
				)
			)
		)
	)
	(footprint ""
		(layer "F.Cu")
		(at 19.685 -183.6928 90)
		(property "Reference" "R9025"
			(at 0 0 90)
			(layer "F.SilkS")
			(hide yes)
			(effects
				(font
					(size 1.27 1.27)
				)
			)
		)
		(property "Value" "100R2D-GP"
			(at 0.064008 -3.993896 90)
			(unlocked yes)
			(layer "F.Fab")
			(hide yes)
			(effects
				(font
					(size 1.016 1.016)
					(thickness 0.1524)
				)
			)
		)
		(property "Device Type" "R402H14"
			(at 0.064008 -5.517896 90)
			(unlocked yes)
			(layer "F.Fab")
			(hide yes)
			(effects
				(font
					(size 1.016 1.016)
					(thickness 0.1524)
				)
			)
		)
		(duplicate_pad_numbers_are_jumpers no)
		(fp_line
			(start 0.508 -0.9398)
			(end -0.508 -0.9398)
			(stroke
				(width 0.1524)
				(type default)
			)
			(layer "F.SilkS")
		)
		(fp_line
			(start -0.508 -0.9398)
			(end -0.508 0.9398)
			(stroke
				(width 0.1524)
				(type default)
			)
			(layer "F.SilkS")
		)
		(fp_rect
			(start -0.508 0.9398)
			(end 0.508 -0.9398)
			(stroke
				(width 0)
				(type default)
			)
			(fill no)
			(layer "F.CrtYd")
		)
		(fp_rect
			(start -0.508 0.9398)
			(end 0.508 -0.9398)
			(stroke
				(width 0)
				(type default)
			)
			(fill no)
			(layer "F.Fab")
		)
		(pad "1" smd custom
			(at 0 -0.4445 90)
			(size 0.1397 0.1397)
			(layers "F.Cu" "F.Mask" "F.Paste")
			(net "MB0_TEMP")
			(options
				(clearance outline)
				(anchor circle)
			)
			(primitives
				(gr_poly
					(pts
						(arc
							(start -0.1778 -0.2794)
							(mid -0.249642 -0.249642)
							(end -0.2794 -0.1778)
						)
						(arc
							(start -0.2794 0.1778)
							(mid -0.249642 0.249642)
							(end -0.1778 0.2794)
						)
						(arc
							(start 0.1778 0.2794)
							(mid 0.249642 0.249642)
							(end 0.2794 0.1778)
						)
						(arc
							(start 0.2794 -0.1778)
							(mid 0.249642 -0.249642)
							(end 0.1778 -0.2794)
						)
					)
					(width 0)
					(fill yes)
				)
			)
		)
		(pad "2" smd custom
			(at 0 0.4445 90)
			(size 0.1397 0.1397)
			(layers "F.Cu" "F.Mask" "F.Paste")
			(net "MB0_TEMP_C")
			(options
				(clearance outline)
				(anchor circle)
			)
			(primitives
				(gr_poly
					(pts
						(arc
							(start -0.1778 -0.2794)
							(mid -0.249642 -0.249642)
							(end -0.2794 -0.1778)
						)
						(arc
							(start -0.2794 0.1778)
							(mid -0.249642 0.249642)
							(end -0.1778 0.2794)
						)
						(arc
							(start 0.1778 0.2794)
							(mid 0.249642 0.249642)
							(end 0.2794 0.1778)
						)
						(arc
							(start 0.2794 -0.1778)
							(mid 0.249642 -0.249642)
							(end 0.1778 -0.2794)
						)
					)
					(width 0)
					(fill yes)
				)
			)
		)
	)
	(footprint ""
		(layer "F.Cu")
		(at 140.335 -34.949638 -90)
		(property "Reference" "R206"
			(at 0 0 270)
			(layer "F.SilkS")
			(hide yes)
			(effects
				(font
					(size 1.27 1.27)
				)
			)
		)
		(property "Value" "4K7R2F-GP"
			(at 0.064008 -3.993896 270)
			(unlocked yes)
			(layer "F.Fab")
			(hide yes)
			(effects
				(font
					(size 1.016 1.016)
					(thickness 0.1524)
				)
			)
		)
		(property "Device Type" "R402H16"
			(at 0.064008 -5.517896 270)
			(unlocked yes)
			(layer "F.Fab")
			(hide yes)
			(effects
				(font
					(size 1.016 1.016)
					(thickness 0.1524)
				)
			)
		)
		(duplicate_pad_numbers_are_jumpers no)
		(fp_line
			(start -0.508 -0.9398)
			(end -0.508 0.9398)
			(stroke
				(width 0.1524)
				(type default)
			)
			(layer "F.SilkS")
		)
		(fp_line
			(start 0.508 -0.9398)
			(end -0.508 -0.9398)
			(stroke
				(width 0.1524)
				(type default)
			)
			(layer "F.SilkS")
		)
		(fp_rect
			(start -0.508 0.9398)
			(end 0.508 -0.9398)
			(stroke
				(width 0)
				(type default)
			)
			(fill no)
			(layer "F.CrtYd")
		)
		(fp_rect
			(start -0.508 0.9398)
			(end 0.508 -0.9398)
			(stroke
				(width 0)
				(type default)
			)
			(fill no)
			(layer "F.Fab")
		)
		(pad "1" smd custom
			(at 0 -0.4445 270)
			(size 0.1397 0.1397)
			(layers "F.Cu" "F.Mask" "F.Paste")
			(net "CLK_P_2_R")
			(options
				(clearance outline)
				(anchor circle)
			)
			(primitives
				(gr_poly
					(pts
						(arc
							(start -0.1778 -0.2794)
							(mid -0.249642 -0.249642)
							(end -0.2794 -0.1778)
						)
						(arc
							(start -0.2794 0.1778)
							(mid -0.249642 0.249642)
							(end -0.1778 0.2794)
						)
						(arc
							(start 0.1778 0.2794)
							(mid 0.249642 0.249642)
							(end 0.2794 0.1778)
						)
						(arc
							(start 0.2794 -0.1778)
							(mid 0.249642 -0.249642)
							(end 0.1778 -0.2794)
						)
					)
					(width 0)
					(fill yes)
				)
			)
		)
		(pad "2" smd custom
			(at 0 0.4445 270)
			(size 0.1397 0.1397)
			(layers "F.Cu" "F.Mask" "F.Paste")
			(net "GND")
			(options
				(clearance outline)
				(anchor circle)
			)
			(primitives
				(gr_poly
					(pts
						(arc
							(start -0.1778 -0.2794)
							(mid -0.249642 -0.249642)
							(end -0.2794 -0.1778)
						)
						(arc
							(start -0.2794 0.1778)
							(mid -0.249642 0.249642)
							(end -0.1778 0.2794)
						)
						(arc
							(start 0.1778 0.2794)
							(mid 0.249642 0.249642)
							(end 0.2794 0.1778)
						)
						(arc
							(start 0.2794 -0.1778)
							(mid 0.249642 -0.249642)
							(end 0.1778 -0.2794)
						)
					)
					(width 0)
					(fill yes)
				)
			)
		)
	)
)
